(kicad_pcb
	(version 20241229)
	(generator "pcbnew")
	(generator_version "9.0")
	(general
		(thickness 1.6642)
		(legacy_teardrops no)
	)
	(paper "A3")
	(title_block
		(title "PolarFire SoM")
		(date "2025-07-22")
		(rev "1.1.4")
		(company "Antmicro Ltd")
		(comment 1 "www.antmicro.com")
		(comment 9 "footprints 367-370 of 470")
	)
	(layers
		(0 "F.Cu" mixed)
		(4 "In1.Cu" power)
		(6 "In2.Cu" signal)
		(8 "In3.Cu" power)
		(10 "In4.Cu" signal)
		(12 "In5.Cu" power)
		(14 "In6.Cu" power)
		(16 "In7.Cu" signal)
		(18 "In8.Cu" power)
		(20 "In9.Cu" signal)
		(22 "In10.Cu" power)
		(24 "In11.Cu" signal)
		(26 "In12.Cu" signal)
		(2 "B.Cu" mixed)
		(9 "F.Adhes" user "F.Adhesive")
		(11 "B.Adhes" user "B.Adhesive")
		(13 "F.Paste" user)
		(15 "B.Paste" user)
		(5 "F.SilkS" user "F.Silkscreen")
		(7 "B.SilkS" user "B.Silkscreen")
		(1 "F.Mask" user)
		(3 "B.Mask" user)
		(17 "Dwgs.User" user "User.Drawings")
		(19 "Cmts.User" user "User.Comments")
		(21 "Eco1.User" user "User.Eco1")
		(23 "Eco2.User" user "User.Eco2")
		(25 "Edge.Cuts" user)
		(27 "Margin" user)
		(31 "F.CrtYd" user "F.Courtyard")
		(29 "B.CrtYd" user "B.Courtyard")
		(35 "F.Fab" user)
		(33 "B.Fab" user)
	)
	(footprint "antmicro-footprints:R_0402_1005Metric"
		(layer "B.Cu")
		(at 184.75 120.85 90)
		(descr "Resistor SMD 0402")
		(tags "resistor SMD 0402")
		(property "Reference" "R7"
			(at 0.4 -1.5 270)
			(layer "B.SilkS")
			(effects
				(font
					(size 0.7 0.7)
					(thickness 0.15)
				)
				(justify left bottom mirror)
			)
		)
		(property "Value" "R_0R_0402"
			(at -1.011843 -1.772047 270)
			(layer "B.Fab")
			(hide yes)
			(effects
				(font
					(size 0.7 0.7)
					(thickness 0.15)
				)
				(justify left bottom mirror)
			)
		)
		(property "Datasheet" "https://industrial.panasonic.com/cdbs/www-data/pdf/RDA0000/AOA0000C301.pdf"
			(at 0 0 90)
			(layer "F.Fab")
			(hide yes)
			(effects
				(font
					(size 1.27 1.27)
					(thickness 0.15)
				)
			)
		)
		(property "Description" "SMD Chip Resistor, Jumper, 0 ohm, 100 mW, 0402 [1005 Metric], Thick Film, General Purpose"
			(at 0 0 90)
			(layer "F.Fab")
			(hide yes)
			(effects
				(font
					(size 1.27 1.27)
					(thickness 0.15)
				)
			)
		)
		(property "Author" "Antmicro"
			(at 305.6 -63.9 0)
			(layer "B.Fab")
			(hide yes)
			(effects
				(font
					(size 1 1)
					(thickness 0.15)
				)
				(justify mirror)
			)
		)
		(property "Current" "1A"
			(at 305.6 -63.9 0)
			(layer "B.Fab")
			(hide yes)
			(effects
				(font
					(size 1 1)
					(thickness 0.15)
				)
				(justify mirror)
			)
		)
		(property "License" "Apache-2.0"
			(at 305.6 -63.9 0)
			(layer "B.Fab")
			(hide yes)
			(effects
				(font
					(size 1 1)
					(thickness 0.15)
				)
				(justify mirror)
			)
		)
		(property "MPN" "ERJ2GE0R00X"
			(at 305.6 -63.9 0)
			(layer "B.Fab")
			(hide yes)
			(effects
				(font
					(size 1 1)
					(thickness 0.15)
				)
				(justify mirror)
			)
		)
		(property "Manufacturer" "Panasonic"
			(at 305.6 -63.9 0)
			(layer "B.Fab")
			(hide yes)
			(effects
				(font
					(size 1 1)
					(thickness 0.15)
				)
				(justify mirror)
			)
		)
		(property "Public" ""
			(at 305.6 -63.9 0)
			(layer "B.Fab")
			(hide yes)
			(effects
				(font
					(size 1 1)
					(thickness 0.15)
				)
				(justify mirror)
			)
		)
		(property "Tolerance" "~"
			(at 305.6 -63.9 0)
			(layer "B.Fab")
			(hide yes)
			(effects
				(font
					(size 1 1)
					(thickness 0.15)
				)
				(justify mirror)
			)
		)
		(property "Val" "0R"
			(at 305.6 -63.9 0)
			(layer "B.Fab")
			(hide yes)
			(effects
				(font
					(size 1 1)
					(thickness 0.15)
				)
				(justify mirror)
			)
		)
		(sheetname "/Supply/")
		(sheetfile "supply.kicad_sch")
		(attr smd)
		(fp_rect
			(start -0.925 0.47)
			(end 0.925 -0.47)
			(stroke
				(width 0.05)
				(type default)
			)
			(fill no)
			(layer "B.CrtYd")
		)
		(fp_rect
			(start -0.5 0.25)
			(end 0.5 -0.25)
			(stroke
				(width 0.15)
				(type solid)
			)
			(fill no)
			(layer "B.Fab")
		)
		(fp_text user "${REFERENCE}"
			(at -0.95 -3.168 270)
			(layer "B.Fab")
			(effects
				(font
					(size 0.7 0.7)
					(thickness 0.15)
				)
				(justify left bottom mirror)
			)
		)
		(fp_text user "Author: Antmicro"
			(at -0.95 -4.169 270)
			(layer "B.Fab")
			(effects
				(font
					(size 0.7 0.7)
					(thickness 0.15)
				)
				(justify left bottom mirror)
			)
		)
		(fp_text user "License: Apache-2.0"
			(at -0.95 -5.169 270)
			(layer "B.Fab")
			(effects
				(font
					(size 0.7 0.7)
					(thickness 0.15)
				)
				(justify left bottom mirror)
			)
		)
		(pad "1" smd roundrect
			(at -0.48 0 90)
			(size 0.59 0.64)
			(layers "B.Cu" "B.Mask" "B.Paste")
			(roundrect_rratio 0.25)
			(net 187 "/Supply/PWRON")
			(pintype "passive")
		)
		(pad "2" smd roundrect
			(at 0.48 0 90)
			(size 0.59 0.64)
			(layers "B.Cu" "B.Mask" "B.Paste")
			(roundrect_rratio 0.25)
			(net 212 "GLOBAL_EN")
			(pintype "passive")
		)
	)
	(footprint "antmicro-footprints:R_0402_1005Metric"
		(layer "B.Cu")
		(at 226.63 128.2 180)
		(descr "Resistor SMD 0402")
		(tags "resistor SMD 0402")
		(property "Reference" "R70"
			(at -2.92 -0.45 180)
			(layer "B.SilkS")
			(effects
				(font
					(size 0.7 0.7)
					(thickness 0.15)
				)
				(justify left bottom mirror)
			)
		)
		(property "Value" "R_590R_0402"
			(at -1.011843 -1.772047 0)
			(layer "B.Fab")
			(hide yes)
			(effects
				(font
					(size 0.7 0.7)
					(thickness 0.15)
				)
				(justify left bottom mirror)
			)
		)
		(property "Datasheet" "https://www.bourns.com/docs/product-datasheets/cr.pdf"
			(at 0 0 180)
			(layer "F.Fab")
			(hide yes)
			(effects
				(font
					(size 1.27 1.27)
					(thickness 0.15)
				)
			)
		)
		(property "Description" "SMD Chip Resistor, 590 ohm, ± 1%, 100 mW, 0402 [1005 Metric], Thick Film, Precision"
			(at 0 0 180)
			(layer "F.Fab")
			(hide yes)
			(effects
				(font
					(size 1.27 1.27)
					(thickness 0.15)
				)
			)
		)
		(property "Author" "Antmicro"
			(at 453.26 256.4 0)
			(layer "B.Fab")
			(hide yes)
			(effects
				(font
					(size 1 1)
					(thickness 0.15)
				)
				(justify mirror)
			)
		)
		(property "License" "Apache-2.0"
			(at 453.26 256.4 0)
			(layer "B.Fab")
			(hide yes)
			(effects
				(font
					(size 1 1)
					(thickness 0.15)
				)
				(justify mirror)
			)
		)
		(property "MPN" "CR0402-FX-5900GLF"
			(at 453.26 256.4 0)
			(layer "B.Fab")
			(hide yes)
			(effects
				(font
					(size 1 1)
					(thickness 0.15)
				)
				(justify mirror)
			)
		)
		(property "Manufacturer" "Bourns"
			(at 453.26 256.4 0)
			(layer "B.Fab")
			(hide yes)
			(effects
				(font
					(size 1 1)
					(thickness 0.15)
				)
				(justify mirror)
			)
		)
		(property "Public" ""
			(at 453.26 256.4 0)
			(layer "B.Fab")
			(hide yes)
			(effects
				(font
					(size 1 1)
					(thickness 0.15)
				)
				(justify mirror)
			)
		)
		(property "Tolerance" "1%"
			(at 453.26 256.4 0)
			(layer "B.Fab")
			(hide yes)
			(effects
				(font
					(size 1 1)
					(thickness 0.15)
				)
				(justify mirror)
			)
		)
		(property "Val" "590R"
			(at 453.26 256.4 0)
			(layer "B.Fab")
			(hide yes)
			(effects
				(font
					(size 1 1)
					(thickness 0.15)
				)
				(justify mirror)
			)
		)
		(sheetname "/FPGA GPIO/")
		(sheetfile "fpga-gpio.kicad_sch")
		(attr smd)
		(fp_rect
			(start -0.925 0.47)
			(end 0.925 -0.47)
			(stroke
				(width 0.05)
				(type default)
			)
			(fill no)
			(layer "B.CrtYd")
		)
		(fp_rect
			(start -0.5 0.25)
			(end 0.5 -0.25)
			(stroke
				(width 0.15)
				(type solid)
			)
			(fill no)
			(layer "B.Fab")
		)
		(fp_text user "License: Apache-2.0"
			(at -0.95 -5.169 0)
			(layer "B.Fab")
			(effects
				(font
					(size 0.7 0.7)
					(thickness 0.15)
				)
				(justify left bottom mirror)
			)
		)
		(fp_text user "${REFERENCE}"
			(at -0.95 -3.168 0)
			(layer "B.Fab")
			(effects
				(font
					(size 0.7 0.7)
					(thickness 0.15)
				)
				(justify left bottom mirror)
			)
		)
		(fp_text user "Author: Antmicro"
			(at -0.95 -4.169 0)
			(layer "B.Fab")
			(effects
				(font
					(size 0.7 0.7)
					(thickness 0.15)
				)
				(justify left bottom mirror)
			)
		)
		(pad "1" smd roundrect
			(at -0.48 0 180)
			(size 0.59 0.64)
			(layers "B.Cu" "B.Mask" "B.Paste")
			(roundrect_rratio 0.25)
			(net 542 "Net-(Q8-D)")
			(pintype "passive")
		)
		(pad "2" smd roundrect
			(at 0.48 0 180)
			(size 0.59 0.64)
			(layers "B.Cu" "B.Mask" "B.Paste")
			(roundrect_rratio 0.25)
			(net 385 "Net-(D6-C_{R})")
			(pintype "passive")
		)
	)
	(footprint "antmicro-footprints:R_0402_1005Metric"
		(layer "B.Cu")
		(at 211.5 147 -90)
		(descr "Resistor SMD 0402")
		(tags "resistor SMD 0402")
		(property "Reference" "R85"
			(at 0.9 -0.27 90)
			(layer "B.SilkS")
			(effects
				(font
					(size 0.7 0.7)
					(thickness 0.15)
				)
				(justify left bottom mirror)
			)
		)
		(property "Value" "R_10k_0402"
			(at -1.011843 -1.772047 90)
			(layer "B.Fab")
			(hide yes)
			(effects
				(font
					(size 0.7 0.7)
					(thickness 0.15)
				)
				(justify left bottom mirror)
			)
		)
		(property "Datasheet" "https://www.bourns.com/docs/product-datasheets/cr.pdf"
			(at 0 0 270)
			(layer "F.Fab")
			(hide yes)
			(effects
				(font
					(size 1.27 1.27)
					(thickness 0.15)
				)
			)
		)
		(property "Description" "SMD Chip Resistor, 10 kohm, ± 1%, 62.5 mW, 0402 [1005 Metric], Thick Film, General Purpose"
			(at 0 0 270)
			(layer "F.Fab")
			(hide yes)
			(effects
				(font
					(size 1.27 1.27)
					(thickness 0.15)
				)
			)
		)
		(property "Author" "Antmicro"
			(at 64.5 358.5 0)
			(layer "B.Fab")
			(hide yes)
			(effects
				(font
					(size 1 1)
					(thickness 0.15)
				)
				(justify mirror)
			)
		)
		(property "License" "Apache-2.0"
			(at 64.5 358.5 0)
			(layer "B.Fab")
			(hide yes)
			(effects
				(font
					(size 1 1)
					(thickness 0.15)
				)
				(justify mirror)
			)
		)
		(property "MPN" "CR0402-FX-1002GLF"
			(at 64.5 358.5 0)
			(layer "B.Fab")
			(hide yes)
			(effects
				(font
					(size 1 1)
					(thickness 0.15)
				)
				(justify mirror)
			)
		)
		(property "Manufacturer" "Bourns"
			(at 64.5 358.5 0)
			(layer "B.Fab")
			(hide yes)
			(effects
				(font
					(size 1 1)
					(thickness 0.15)
				)
				(justify mirror)
			)
		)
		(property "Public" ""
			(at 64.5 358.5 0)
			(layer "B.Fab")
			(hide yes)
			(effects
				(font
					(size 1 1)
					(thickness 0.15)
				)
				(justify mirror)
			)
		)
		(property "Tolerance" "1%"
			(at 64.5 358.5 0)
			(layer "B.Fab")
			(hide yes)
			(effects
				(font
					(size 1 1)
					(thickness 0.15)
				)
				(justify mirror)
			)
		)
		(property "Val" "10k"
			(at 64.5 358.5 0)
			(layer "B.Fab")
			(hide yes)
			(effects
				(font
					(size 1 1)
					(thickness 0.15)
				)
				(justify mirror)
			)
		)
		(sheetname "/USB/")
		(sheetfile "usb.kicad_sch")
		(attr smd)
		(fp_rect
			(start -0.925 0.47)
			(end 0.925 -0.47)
			(stroke
				(width 0.05)
				(type default)
			)
			(fill no)
			(layer "B.CrtYd")
		)
		(fp_rect
			(start -0.5 0.25)
			(end 0.5 -0.25)
			(stroke
				(width 0.15)
				(type solid)
			)
			(fill no)
			(layer "B.Fab")
		)
		(fp_text user "Author: Antmicro"
			(at -0.95 -4.169 90)
			(layer "B.Fab")
			(effects
				(font
					(size 0.7 0.7)
					(thickness 0.15)
				)
				(justify left bottom mirror)
			)
		)
		(fp_text user "License: Apache-2.0"
			(at -0.95 -5.169 90)
			(layer "B.Fab")
			(effects
				(font
					(size 0.7 0.7)
					(thickness 0.15)
				)
				(justify left bottom mirror)
			)
		)
		(fp_text user "${REFERENCE}"
			(at -0.95 -3.168 90)
			(layer "B.Fab")
			(effects
				(font
					(size 0.7 0.7)
					(thickness 0.15)
				)
				(justify left bottom mirror)
			)
		)
		(pad "1" smd roundrect
			(at -0.48 0 270)
			(size 0.59 0.64)
			(layers "B.Cu" "B.Mask" "B.Paste")
			(roundrect_rratio 0.25)
			(net 379 "/USB/RESETB")
			(pintype "passive")
		)
		(pad "2" smd roundrect
			(at 0.48 0 270)
			(size 0.59 0.64)
			(layers "B.Cu" "B.Mask" "B.Paste")
			(roundrect_rratio 0.25)
			(net 649 "VDD")
			(pintype "passive")
		)
	)
	(footprint "antmicro-footprints:C_0402_1005Metric"
		(layer "B.Cu")
		(at 215.6925 132.197 -90)
		(descr "Capacitor SMD 0402")
		(tags "capacitor SMD 0402")
		(property "Reference" "C73"
			(at -0.437 -2.1375 90)
			(layer "B.SilkS")
			(effects
				(font
					(size 0.7 0.7)
					(thickness 0.15)
				)
				(justify left bottom mirror)
			)
		)
		(property "Value" "C_100n_0402"
			(at -1.022927 -2.155213 90)
			(layer "B.Fab")
			(hide yes)
			(effects
				(font
					(size 0.7 0.7)
					(thickness 0.15)
				)
				(justify left bottom mirror)
			)
		)
		(property "Datasheet" "https://www.murata.com/products/productdetail?partno=GRM155R61H104KE14%23"
			(at 0 0 270)
			(layer "F.Fab")
			(hide yes)
			(effects
				(font
					(size 1.27 1.27)
					(thickness 0.15)
				)
			)
		)
		(property "Description" "SMD Multilayer Ceramic Capacitor, 0.1 µF, 50 V, 0402 [1005 Metric], ± 10%, X5R, GRM Series"
			(at 0 0 270)
			(layer "F.Fab")
			(hide yes)
			(effects
				(font
					(size 1.27 1.27)
					(thickness 0.15)
				)
			)
		)
		(property "Author" "Antmicro"
			(at 83.4955 347.8895 0)
			(layer "B.Fab")
			(hide yes)
			(effects
				(font
					(size 1 1)
					(thickness 0.15)
				)
				(justify mirror)
			)
		)
		(property "Dielectric" "X5R"
			(at 83.4955 347.8895 0)
			(layer "B.Fab")
			(hide yes)
			(effects
				(font
					(size 1 1)
					(thickness 0.15)
				)
				(justify mirror)
			)
		)
		(property "License" "Apache-2.0"
			(at 83.4955 347.8895 0)
			(layer "B.Fab")
			(hide yes)
			(effects
				(font
					(size 1 1)
					(thickness 0.15)
				)
				(justify mirror)
			)
		)
		(property "MPN" "GRM155R61H104KE14D"
			(at 83.4955 347.8895 0)
			(layer "B.Fab")
			(hide yes)
			(effects
				(font
					(size 1 1)
					(thickness 0.15)
				)
				(justify mirror)
			)
		)
		(property "Manufacturer" "Murata"
			(at 83.4955 347.8895 0)
			(layer "B.Fab")
			(hide yes)
			(effects
				(font
					(size 1 1)
					(thickness 0.15)
				)
				(justify mirror)
			)
		)
		(property "Public" ""
			(at 83.4955 347.8895 0)
			(layer "B.Fab")
			(hide yes)
			(effects
				(font
					(size 1 1)
					(thickness 0.15)
				)
				(justify mirror)
			)
		)
		(property "Val" "100n"
			(at 83.4955 347.8895 0)
			(layer "B.Fab")
			(hide yes)
			(effects
				(font
					(size 1 1)
					(thickness 0.15)
				)
				(justify mirror)
			)
		)
		(property "Voltage" "50V"
			(at 83.4955 347.8895 0)
			(layer "B.Fab")
			(hide yes)
			(effects
				(font
					(size 1 1)
					(thickness 0.15)
				)
				(justify mirror)
			)
		)
		(sheetname "/Memory/")
		(sheetfile "memory.kicad_sch")
		(attr smd)
		(fp_rect
			(start -0.925 0.47)
			(end 0.925 -0.47)
			(stroke
				(width 0.05)
				(type default)
			)
			(fill no)
			(layer "B.CrtYd")
		)
		(fp_line
			(start -0.494 0.25)
			(end 0.504 0.25)
			(stroke
				(width 0.15)
				(type solid)
			)
			(layer "B.Fab")
		)
		(fp_line
			(start 0.504 0.25)
			(end 0.504 -0.248)
			(stroke
				(width 0.15)
				(type solid)
			)
			(layer "B.Fab")
		)
		(fp_line
			(start -0.494 -0.248)
			(end -0.494 0.25)
			(stroke
				(width 0.15)
				(type solid)
			)
			(layer "B.Fab")
		)
		(fp_line
			(start 0.504 -0.248)
			(end -0.494 -0.248)
			(stroke
				(width 0.15)
				(type solid)
			)
			(layer "B.Fab")
		)
		(fp_text user "Author: Antmicro"
			(at -0.939 -3.399 90)
			(layer "B.Fab")
			(effects
				(font
					(size 0.7 0.7)
					(thickness 0.15)
				)
				(justify left bottom mirror)
			)
		)
		(fp_text user "License: Apache-2.0"
			(at -0.939 -5.799 90)
			(layer "B.Fab")
			(effects
				(font
					(size 0.7 0.7)
					(thickness 0.15)
				)
				(justify left bottom mirror)
			)
		)
		(fp_text user "${REFERENCE}"
			(at -0.939 -4.599 90)
			(layer "B.Fab")
			(effects
				(font
					(size 0.7 0.7)
					(thickness 0.15)
				)
				(justify left bottom mirror)
			)
		)
		(pad "1" smd roundrect
			(at -0.48 0 270)
			(size 0.59 0.64)
			(layers "B.Cu" "B.Mask" "B.Paste")
			(roundrect_rratio 0.25)
			(net 417 "GND")
			(pintype "passive")
		)
		(pad "2" smd roundrect
			(at 0.48 0 270)
			(size 0.59 0.64)
			(layers "B.Cu" "B.Mask" "B.Paste")
			(roundrect_rratio 0.25)
			(net 50 "+3V3")
			(pintype "passive")
		)
	)
)
